(kicad_pcb
	(version 20260206)
	(generator "pcbnew")
	(generator_version "10.0")
	(general
		(thickness 1.6)
		(legacy_teardrops no)
	)
	(paper "A4")
	(title_block
		(title "baseboard — 13948-1b.1110WZS1818.brd")
		(comment 1 "Honey Badger (Wiwynn) / footprints 853-859 of 2523")
	)
	(layers
		(0 "F.Cu" signal "TOP")
		(4 "In1.Cu" signal "L2GND")
		(6 "In2.Cu" signal "L3")
		(8 "In3.Cu" signal "L4VCC")
		(10 "In4.Cu" signal "L5VCC")
		(12 "In5.Cu" signal "L6")
		(14 "In6.Cu" signal "L7GND")
		(2 "B.Cu" signal "BOTTOM")
		(9 "F.Adhes" user "F.Adhesive")
		(11 "B.Adhes" user "B.Adhesive")
		(13 "F.Paste" user "Package Geometry/Pastemask Top")
		(15 "B.Paste" user "Package Geometry/Pastemask Bottom")
		(5 "F.SilkS" user "Ref Des/Silkscreen Top")
		(7 "B.SilkS" user "Ref Des/Silkscreen Bottom")
		(1 "F.Mask" user "Board Geometry/Soldermask Top")
		(3 "B.Mask" user "Board Geometry/Soldermask Bottom")
		(17 "Dwgs.User" user "User.Drawings")
		(19 "Cmts.User" user "User.Comments")
		(21 "Eco1.User" user "User.Eco1")
		(23 "Eco2.User" user "User.Eco2")
		(25 "Edge.Cuts" user "Board Geometry/Outline")
		(27 "Margin" user)
		(31 "F.CrtYd" user "Package Geometry/Place Bound Top")
		(29 "B.CrtYd" user "Package Geometry/Place Bound Bottom")
		(35 "F.Fab" user "Ref Des/Assembly Top")
		(33 "B.Fab" user "Ref Des/Assembly Bottom")
	)
	(footprint ""
		(layer "F.Cu")
		(at 326.898 -114.3)
		(property "Reference" "PC25"
			(at 0 0 0)
			(layer "F.SilkS")
			(hide yes)
			(effects
				(font
					(size 1.27 1.27)
				)
			)
		)
		(property "Value" "SCD1U25V3KX-GP"
			(at 0 -2.8194 0)
			(unlocked yes)
			(layer "F.Fab")
			(hide yes)
			(effects
				(font
					(size 1.016 1.016)
					(thickness 0.1524)
				)
			)
		)
		(property "Device Type" "C603H36"
			(at 0 -4.3434 0)
			(unlocked yes)
			(layer "F.Fab")
			(hide yes)
			(effects
				(font
					(size 1.016 1.016)
					(thickness 0.1524)
				)
			)
		)
		(duplicate_pad_numbers_are_jumpers no)
		(fp_line
			(start 0.508 0)
			(end -0.508 0)
			(stroke
				(width 0.2032)
				(type default)
			)
			(layer "F.SilkS")
		)
		(fp_rect
			(start -0.5842 1.3335)
			(end 0.5842 -1.3335)
			(stroke
				(width 0)
				(type default)
			)
			(fill no)
			(layer "F.CrtYd")
		)
		(fp_rect
			(start -0.5842 1.3335)
			(end 0.5842 -1.3335)
			(stroke
				(width 0)
				(type default)
			)
			(fill no)
			(layer "F.Fab")
		)
		(pad "1" smd custom
			(at 0 -0.762)
			(size 0.2159 0.2159)
			(layers "F.Cu" "F.Mask" "F.Paste")
			(net "P3V3_STBY_VIN")
			(options
				(clearance outline)
				(anchor circle)
			)
			(primitives
				(gr_poly
					(pts
						(arc
							(start -0.3302 -0.4318)
							(mid -0.402042 -0.402042)
							(end -0.4318 -0.3302)
						)
						(arc
							(start -0.4318 0.3302)
							(mid -0.402042 0.402042)
							(end -0.3302 0.4318)
						)
						(arc
							(start 0.3302 0.4318)
							(mid 0.402042 0.402042)
							(end 0.4318 0.3302)
						)
						(arc
							(start 0.4318 -0.3302)
							(mid 0.402042 -0.402042)
							(end 0.3302 -0.4318)
						)
					)
					(width 0)
					(fill yes)
				)
			)
		)
		(pad "2" smd custom
			(at 0 0.762)
			(size 0.2159 0.2159)
			(layers "F.Cu" "F.Mask" "F.Paste")
			(net "GND")
			(options
				(clearance outline)
				(anchor circle)
			)
			(primitives
				(gr_poly
					(pts
						(arc
							(start -0.3302 -0.4318)
							(mid -0.402042 -0.402042)
							(end -0.4318 -0.3302)
						)
						(arc
							(start -0.4318 0.3302)
							(mid -0.402042 0.402042)
							(end -0.3302 0.4318)
						)
						(arc
							(start 0.3302 0.4318)
							(mid 0.402042 0.402042)
							(end 0.4318 0.3302)
						)
						(arc
							(start 0.4318 -0.3302)
							(mid 0.402042 -0.402042)
							(end 0.3302 -0.4318)
						)
					)
					(width 0)
					(fill yes)
				)
			)
		)
	)
	(footprint ""
		(layer "F.Cu")
		(at 229.743 -20.066)
		(property "Reference" "SR807"
			(at 0 0 0)
			(layer "F.SilkS")
			(hide yes)
			(effects
				(font
					(size 1.27 1.27)
				)
			)
		)
		(property "Value" "0R3J-0-U-GP"
			(at -0.0254 -2.5146 0)
			(unlocked yes)
			(layer "F.Fab")
			(hide yes)
			(effects
				(font
					(size 1.016 1.016)
					(thickness 0.1524)
				)
			)
		)
		(property "Device Type" "R603H22"
			(at -0.0254 -4.0386 0)
			(unlocked yes)
			(layer "F.Fab")
			(hide yes)
			(effects
				(font
					(size 1.016 1.016)
					(thickness 0.1524)
				)
			)
		)
		(duplicate_pad_numbers_are_jumpers no)
		(fp_line
			(start -0.4826 0)
			(end -0.2032 0)
			(stroke
				(width 0.2032)
				(type default)
			)
			(layer "F.SilkS")
		)
		(fp_line
			(start 0.2032 0)
			(end 0.4826 0)
			(stroke
				(width 0.2032)
				(type default)
			)
			(layer "F.SilkS")
		)
		(fp_rect
			(start -0.5842 1.3335)
			(end 0.5842 -1.3335)
			(stroke
				(width 0)
				(type default)
			)
			(fill no)
			(layer "F.CrtYd")
		)
		(fp_rect
			(start -0.5842 1.3335)
			(end 0.5842 -1.3335)
			(stroke
				(width 0)
				(type default)
			)
			(fill no)
			(layer "F.Fab")
		)
		(pad "1" smd custom
			(at 0 -0.762)
			(size 0.2159 0.2159)
			(layers "F.Cu" "F.Mask" "F.Paste")
			(net "P1V8_E")
			(options
				(clearance outline)
				(anchor circle)
			)
			(primitives
				(gr_poly
					(pts
						(arc
							(start -0.3302 -0.4318)
							(mid -0.402042 -0.402042)
							(end -0.4318 -0.3302)
						)
						(arc
							(start -0.4318 0.3302)
							(mid -0.402042 0.402042)
							(end -0.3302 0.4318)
						)
						(arc
							(start 0.3302 0.4318)
							(mid 0.402042 0.402042)
							(end 0.4318 0.3302)
						)
						(arc
							(start 0.4318 -0.3302)
							(mid 0.402042 -0.402042)
							(end 0.3302 -0.4318)
						)
					)
					(width 0)
					(fill yes)
				)
			)
		)
		(pad "2" smd custom
			(at 0 0.762)
			(size 0.2159 0.2159)
			(layers "F.Cu" "F.Mask" "F.Paste")
			(net "3D3V_ICE")
			(options
				(clearance outline)
				(anchor circle)
			)
			(primitives
				(gr_poly
					(pts
						(arc
							(start -0.3302 -0.4318)
							(mid -0.402042 -0.402042)
							(end -0.4318 -0.3302)
						)
						(arc
							(start -0.4318 0.3302)
							(mid -0.402042 0.402042)
							(end -0.3302 0.4318)
						)
						(arc
							(start 0.3302 0.4318)
							(mid 0.402042 0.402042)
							(end 0.4318 0.3302)
						)
						(arc
							(start 0.4318 -0.3302)
							(mid 0.402042 -0.402042)
							(end 0.3302 -0.4318)
						)
					)
					(width 0)
					(fill yes)
				)
			)
		)
	)
	(footprint ""
		(layer "F.Cu")
		(at 261.562596 -53.232812 90)
		(property "Reference" "SR721"
			(at 0 0 90)
			(layer "F.SilkS")
			(hide yes)
			(effects
				(font
					(size 1.27 1.27)
				)
			)
		)
		(property "Value" "4K7R2F-GP"
			(at 0.064008 -3.993896 90)
			(unlocked yes)
			(layer "F.Fab")
			(hide yes)
			(effects
				(font
					(size 1.016 1.016)
					(thickness 0.1524)
				)
			)
		)
		(property "Device Type" "R402H16"
			(at 0.064008 -5.517896 90)
			(unlocked yes)
			(layer "F.Fab")
			(hide yes)
			(effects
				(font
					(size 1.016 1.016)
					(thickness 0.1524)
				)
			)
		)
		(duplicate_pad_numbers_are_jumpers no)
		(fp_line
			(start 0.508 -0.9398)
			(end -0.508 -0.9398)
			(stroke
				(width 0.1524)
				(type default)
			)
			(layer "F.SilkS")
		)
		(fp_line
			(start -0.508 -0.9398)
			(end -0.508 0.9398)
			(stroke
				(width 0.1524)
				(type default)
			)
			(layer "F.SilkS")
		)
		(fp_rect
			(start -0.508 0.9398)
			(end 0.508 -0.9398)
			(stroke
				(width 0)
				(type default)
			)
			(fill no)
			(layer "F.CrtYd")
		)
		(fp_rect
			(start -0.508 0.9398)
			(end 0.508 -0.9398)
			(stroke
				(width 0)
				(type default)
			)
			(fill no)
			(layer "F.Fab")
		)
		(pad "1" smd custom
			(at 0 -0.4445 90)
			(size 0.1397 0.1397)
			(layers "F.Cu" "F.Mask" "F.Paste")
			(net "IOC_EEPROM_A2")
			(options
				(clearance outline)
				(anchor circle)
			)
			(primitives
				(gr_poly
					(pts
						(arc
							(start -0.1778 -0.2794)
							(mid -0.249642 -0.249642)
							(end -0.2794 -0.1778)
						)
						(arc
							(start -0.2794 0.1778)
							(mid -0.249642 0.249642)
							(end -0.1778 0.2794)
						)
						(arc
							(start 0.1778 0.2794)
							(mid 0.249642 0.249642)
							(end 0.2794 0.1778)
						)
						(arc
							(start 0.2794 -0.1778)
							(mid 0.249642 -0.249642)
							(end 0.1778 -0.2794)
						)
					)
					(width 0)
					(fill yes)
				)
			)
		)
		(pad "2" smd custom
			(at 0 0.4445 90)
			(size 0.1397 0.1397)
			(layers "F.Cu" "F.Mask" "F.Paste")
			(net "GND")
			(options
				(clearance outline)
				(anchor circle)
			)
			(primitives
				(gr_poly
					(pts
						(arc
							(start -0.1778 -0.2794)
							(mid -0.249642 -0.249642)
							(end -0.2794 -0.1778)
						)
						(arc
							(start -0.2794 0.1778)
							(mid -0.249642 0.249642)
							(end -0.1778 0.2794)
						)
						(arc
							(start 0.1778 0.2794)
							(mid 0.249642 0.249642)
							(end 0.2794 0.1778)
						)
						(arc
							(start 0.2794 -0.1778)
							(mid 0.249642 -0.249642)
							(end 0.1778 -0.2794)
						)
					)
					(width 0)
					(fill yes)
				)
			)
		)
	)
	(footprint ""
		(layer "F.Cu")
		(at 330.699872 -110.435136 90)
		(property "Reference" "PR28"
			(at 0 0 90)
			(layer "F.SilkS")
			(hide yes)
			(effects
				(font
					(size 1.27 1.27)
				)
			)
		)
		(property "Value" "3D01R5F-GP"
			(at 0 -8.9535 90)
			(unlocked yes)
			(layer "F.Fab")
			(hide yes)
			(effects
				(font
					(size 1.27 1.016)
					(thickness 0.1524)
				)
			)
		)
		(property "Device Type" "R805H24"
			(at 0 -10.6299 90)
			(unlocked yes)
			(layer "F.Fab")
			(hide yes)
			(effects
				(font
					(size 1.27 1.016)
					(thickness 0.1524)
				)
			)
		)
		(duplicate_pad_numbers_are_jumpers no)
		(fp_line
			(start 0.889 -1.7018)
			(end -0.889 -1.7018)
			(stroke
				(width 0.1524)
				(type default)
			)
			(layer "F.SilkS")
		)
		(fp_line
			(start 0.889 -1.7018)
			(end 0.889 -0.381)
			(stroke
				(width 0.1524)
				(type default)
			)
			(layer "F.SilkS")
		)
		(fp_line
			(start -0.889 -1.7018)
			(end -0.889 0.2794)
			(stroke
				(width 0.1524)
				(type default)
			)
			(layer "F.SilkS")
		)
		(fp_line
			(start -0.889 0.0762)
			(end -0.889 1.7018)
			(stroke
				(width 0.1524)
				(type default)
			)
			(layer "F.SilkS")
		)
		(fp_line
			(start 0.889 1.7018)
			(end 0.889 -0.508)
			(stroke
				(width 0.1524)
				(type default)
			)
			(layer "F.SilkS")
		)
		(fp_line
			(start -0.889 1.7018)
			(end 0.889 1.7018)
			(stroke
				(width 0.1524)
				(type default)
			)
			(layer "F.SilkS")
		)
		(fp_poly
			(pts
				(xy 0.9652 -1.778) (xy 0.9652 1.778) (xy -0.9652 1.778) (xy -0.9652 -1.778)
			)
			(stroke
				(width 0)
				(type default)
			)
			(fill no)
			(layer "F.CrtYd")
		)
		(fp_rect
			(start -0.9652 1.778)
			(end 0.9652 -1.778)
			(stroke
				(width 0)
				(type default)
			)
			(fill no)
			(layer "F.Fab")
		)
		(pad "1" smd rect
			(at 0 -0.9652 90)
			(size 1.397 1.143)
			(layers "F.Cu" "F.Mask" "F.Paste")
			(net "P3V3_STBY_SNB")
		)
		(pad "2" smd rect
			(at 0 0.9652 90)
			(size 1.397 1.143)
			(layers "F.Cu" "F.Mask" "F.Paste")
			(net "GND")
		)
	)
	(footprint ""
		(layer "F.Cu")
		(at 308.102 -160.655)
		(property "Reference" "R470"
			(at 0 0 0)
			(layer "F.SilkS")
			(hide yes)
			(effects
				(font
					(size 1.27 1.27)
				)
			)
		)
		(property "Value" "0R2J-2-GP"
			(at 0.064008 -3.993896 0)
			(unlocked yes)
			(layer "F.Fab")
			(hide yes)
			(effects
				(font
					(size 1.016 1.016)
					(thickness 0.1524)
				)
			)
		)
		(property "Device Type" "R402H16"
			(at 0.064008 -5.517896 0)
			(unlocked yes)
			(layer "F.Fab")
			(hide yes)
			(effects
				(font
					(size 1.016 1.016)
					(thickness 0.1524)
				)
			)
		)
		(duplicate_pad_numbers_are_jumpers no)
		(fp_line
			(start -0.508 -0.9398)
			(end -0.508 0.9398)
			(stroke
				(width 0.1524)
				(type default)
			)
			(layer "F.SilkS")
		)
		(fp_line
			(start 0.508 -0.9398)
			(end -0.508 -0.9398)
			(stroke
				(width 0.1524)
				(type default)
			)
			(layer "F.SilkS")
		)
		(fp_rect
			(start -0.508 0.9398)
			(end 0.508 -0.9398)
			(stroke
				(width 0)
				(type default)
			)
			(fill no)
			(layer "F.CrtYd")
		)
		(fp_rect
			(start -0.508 0.9398)
			(end 0.508 -0.9398)
			(stroke
				(width 0)
				(type default)
			)
			(fill no)
			(layer "F.Fab")
		)
		(pad "1" smd custom
			(at 0 -0.4445)
			(size 0.1397 0.1397)
			(layers "F.Cu" "F.Mask" "F.Paste")
			(net "BMC0_SMB10_DAT")
			(options
				(clearance outline)
				(anchor circle)
			)
			(primitives
				(gr_poly
					(pts
						(arc
							(start -0.1778 -0.2794)
							(mid -0.249642 -0.249642)
							(end -0.2794 -0.1778)
						)
						(arc
							(start -0.2794 0.1778)
							(mid -0.249642 0.249642)
							(end -0.1778 0.2794)
						)
						(arc
							(start 0.1778 0.2794)
							(mid 0.249642 0.249642)
							(end 0.2794 0.1778)
						)
						(arc
							(start 0.2794 -0.1778)
							(mid 0.249642 -0.249642)
							(end 0.1778 -0.2794)
						)
					)
					(width 0)
					(fill yes)
				)
			)
		)
		(pad "2" smd custom
			(at 0 0.4445)
			(size 0.1397 0.1397)
			(layers "F.Cu" "F.Mask" "F.Paste")
			(net "BMC_I2C_SDA_10")
			(options
				(clearance outline)
				(anchor circle)
			)
			(primitives
				(gr_poly
					(pts
						(arc
							(start -0.1778 -0.2794)
							(mid -0.249642 -0.249642)
							(end -0.2794 -0.1778)
						)
						(arc
							(start -0.2794 0.1778)
							(mid -0.249642 0.249642)
							(end -0.1778 0.2794)
						)
						(arc
							(start 0.1778 0.2794)
							(mid 0.249642 0.249642)
							(end 0.2794 0.1778)
						)
						(arc
							(start 0.2794 -0.1778)
							(mid 0.249642 -0.249642)
							(end 0.1778 -0.2794)
						)
					)
					(width 0)
					(fill yes)
				)
			)
		)
	)
	(footprint ""
		(layer "F.Cu")
		(at 152.247092 -98.200464 -90)
		(property "Reference" "SL15"
			(at 0 0 270)
			(layer "F.SilkS")
			(hide yes)
			(effects
				(font
					(size 1.27 1.27)
				)
			)
		)
		(property "Value" "MPZ2012S300AT-GP"
			(at 0 -4.2418 270)
			(unlocked yes)
			(layer "F.Fab")
			(hide yes)
			(effects
				(font
					(size 1.016 1.016)
					(thickness 0.1524)
				)
			)
		)
		(property "Device Type" "L805H42"
			(at 0 -5.7912 270)
			(unlocked yes)
			(layer "F.Fab")
			(hide yes)
			(effects
				(font
					(size 1.016 1.016)
					(thickness 0.1524)
				)
			)
		)
		(duplicate_pad_numbers_are_jumpers no)
		(fp_line
			(start -0.889 1.7018)
			(end -0.889 -1.7018)
			(stroke
				(width 0.1524)
				(type default)
			)
			(layer "F.SilkS")
		)
		(fp_line
			(start 0.889 1.7018)
			(end -0.889 1.7018)
			(stroke
				(width 0.1524)
				(type default)
			)
			(layer "F.SilkS")
		)
		(fp_line
			(start -0.889 -1.7018)
			(end 0.889 -1.7018)
			(stroke
				(width 0.1524)
				(type default)
			)
			(layer "F.SilkS")
		)
		(fp_line
			(start 0.889 -1.7018)
			(end 0.889 1.7018)
			(stroke
				(width 0.1524)
				(type default)
			)
			(layer "F.SilkS")
		)
		(fp_rect
			(start -0.9652 1.778)
			(end 0.9652 -1.778)
			(stroke
				(width 0)
				(type default)
			)
			(fill no)
			(layer "F.CrtYd")
		)
		(fp_rect
			(start -0.9652 1.778)
			(end 0.9652 -1.778)
			(stroke
				(width 0)
				(type default)
			)
			(fill no)
			(layer "F.Fab")
		)
		(pad "1" smd rect
			(at 0 -0.9652 270)
			(size 1.397 1.143)
			(layers "F.Cu" "F.Mask" "F.Paste")
			(net "P0V9_E")
		)
		(pad "2" smd rect
			(at 0 0.9652 270)
			(size 1.397 1.143)
			(layers "F.Cu" "F.Mask" "F.Paste")
			(net "GB_VDDA")
		)
	)
	(footprint ""
		(layer "F.Cu")
		(at 225.933 -14.351 90)
		(property "Reference" "Q13"
			(at 0 0 90)
			(layer "F.SilkS")
			(hide yes)
			(effects
				(font
					(size 1.27 1.27)
				)
			)
		)
		(property "Value" "2N7002A-7-GP"
			(at 0.127 -8.9662 90)
			(unlocked yes)
			(layer "F.Fab")
			(hide yes)
			(effects
				(font
					(size 1.016 1.016)
					(thickness 0.1524)
				)
			)
		)
		(property "Device Type" "SOT23DGS2D4H48"
			(at 0.127 -10.4902 90)
			(unlocked yes)
			(layer "F.Fab")
			(hide yes)
			(effects
				(font
					(size 1.016 1.016)
					(thickness 0.1524)
				)
			)
		)
		(duplicate_pad_numbers_are_jumpers no)
		(fp_line
			(start 1.651 -1.778)
			(end -1.651 -1.778)
			(stroke
				(width 0.1524)
				(type default)
			)
			(layer "F.SilkS")
		)
		(fp_line
			(start -1.651 -1.778)
			(end -1.651 1.778)
			(stroke
				(width 0.1524)
				(type default)
			)
			(layer "F.SilkS")
		)
		(fp_line
			(start 1.651 1.778)
			(end 1.651 -1.778)
			(stroke
				(width 0.1524)
				(type default)
			)
			(layer "F.SilkS")
		)
		(fp_line
			(start -1.651 1.778)
			(end 1.651 1.778)
			(stroke
				(width 0.1524)
				(type default)
			)
			(layer "F.SilkS")
		)
		(fp_poly
			(pts
				(xy -1.778 1.8796) (xy -1.778 -1.8796) (xy 1.778 -1.8796) (xy 1.778 1.8796)
			)
			(stroke
				(width 0)
				(type default)
			)
			(fill no)
			(layer "F.CrtYd")
		)
		(fp_poly
			(pts
				(xy -1.778 1.8796) (xy -1.778 -1.8796) (xy 1.778 -1.8796) (xy 1.778 1.8796)
			)
			(stroke
				(width 0)
				(type default)
			)
			(fill no)
			(layer "F.Fab")
		)
		(pad "D" smd custom
			(at 0 -0.9525 90)
			(size 0.1905 0.1905)
			(layers "F.Cu" "F.Mask" "F.Paste")
			(net "ENCLO_LED_RED_D1")
			(options
				(clearance outline)
				(anchor circle)
			)
			(primitives
				(gr_poly
					(pts
						(arc
							(start -0.1778 0.5715)
							(mid -0.321484 0.511984)
							(end -0.381 0.3683)
						)
						(arc
							(start -0.381 -0.3683)
							(mid -0.321484 -0.511984)
							(end -0.1778 -0.5715)
						)
						(arc
							(start 0.1778 -0.5715)
							(mid 0.321484 -0.511984)
							(end 0.381 -0.3683)
						)
						(arc
							(start 0.381 0.3683)
							(mid 0.321484 0.511984)
							(end 0.1778 0.5715)
						)
					)
					(width 0)
					(fill yes)
				)
			)
		)
		(pad "G" smd custom
			(at -0.98425 0.9525 90)
			(size 0.1905 0.1905)
			(layers "F.Cu" "F.Mask" "F.Paste")
			(net "ENCLO_LED_RED_D")
			(options
				(clearance outline)
				(anchor circle)
			)
			(primitives
				(gr_poly
					(pts
						(arc
							(start -0.1778 0.5715)
							(mid -0.321484 0.511984)
							(end -0.381 0.3683)
						)
						(arc
							(start -0.381 -0.3683)
							(mid -0.321484 -0.511984)
							(end -0.1778 -0.5715)
						)
						(arc
							(start 0.1778 -0.5715)
							(mid 0.321484 -0.511984)
							(end 0.381 -0.3683)
						)
						(arc
							(start 0.381 0.3683)
							(mid 0.321484 0.511984)
							(end 0.1778 0.5715)
						)
					)
					(width 0)
					(fill yes)
				)
			)
		)
		(pad "S" smd custom
			(at 0.98425 0.9525 90)
			(size 0.1905 0.1905)
			(layers "F.Cu" "F.Mask" "F.Paste")
			(net "GND")
			(options
				(clearance outline)
				(anchor circle)
			)
			(primitives
				(gr_poly
					(pts
						(arc
							(start -0.1778 0.5715)
							(mid -0.321484 0.511984)
							(end -0.381 0.3683)
						)
						(arc
							(start -0.381 -0.3683)
							(mid -0.321484 -0.511984)
							(end -0.1778 -0.5715)
						)
						(arc
							(start 0.1778 -0.5715)
							(mid 0.321484 -0.511984)
							(end 0.381 -0.3683)
						)
						(arc
							(start 0.381 0.3683)
							(mid 0.321484 0.511984)
							(end 0.1778 0.5715)
						)
					)
					(width 0)
					(fill yes)
				)
			)
		)
	)
)
